(kicad_pcb
	(version 20241229)
	(generator "pcbnew")
	(generator_version "9.0")
	(general
		(thickness 1.711)
		(legacy_teardrops no)
	)
	(paper "A4")
	(title_block
		(title "Antmicro Baseboard for Jetson AGX Thor")
		(date "2026-02-18")
		(rev "1.1.0")
		(company "Antmicro Ltd")
		(comment 1 "www.antmicro.com")
		(comment 9 "footprints 23-27 of 1170")
	)
	(layers
		(0 "F.Cu" signal)
		(4 "In1.Cu" signal)
		(6 "In2.Cu" signal)
		(8 "In3.Cu" signal)
		(10 "In4.Cu" jumper)
		(12 "In5.Cu" signal)
		(14 "In6.Cu" signal)
		(16 "In7.Cu" signal)
		(18 "In8.Cu" signal)
		(2 "B.Cu" signal)
		(9 "F.Adhes" user "F.Adhesive")
		(11 "B.Adhes" user "B.Adhesive")
		(13 "F.Paste" user)
		(15 "B.Paste" user)
		(5 "F.SilkS" user "F.Silkscreen")
		(7 "B.SilkS" user "B.Silkscreen")
		(1 "F.Mask" user)
		(3 "B.Mask" user)
		(17 "Dwgs.User" user "User.Drawings")
		(19 "Cmts.User" user "User.Comments")
		(21 "Eco1.User" user "User.Eco1")
		(23 "Eco2.User" user "User.Eco2")
		(25 "Edge.Cuts" user)
		(27 "Margin" user)
		(31 "F.CrtYd" user "F.Courtyard")
		(29 "B.CrtYd" user "B.Courtyard")
		(35 "F.Fab" user)
		(33 "B.Fab" user)
	)
	(footprint "antmicro-footprints:R_0402_1005Metric"
		(layer "F.Cu")
		(at 182.933525 124.897019 180)
		(descr "Resistor SMD 0402")
		(tags "resistor SMD 0402")
		(property "Reference" "R54"
			(at -1.866475 2.197019 0)
			(layer "F.SilkS")
			(effects
				(font
					(size 0.7 0.7)
					(thickness 0.15)
				)
				(justify right top)
			)
		)
		(property "Value" "R_45k3_0402"
			(at -1.011843 1.772047 0)
			(layer "F.Fab")
			(effects
				(font
					(size 0.7 0.7)
					(thickness 0.15)
				)
				(justify right top)
			)
		)
		(property "Datasheet" "https://www.bourns.com/docs/product-datasheets/cr.pdf"
			(at 0 0 0)
			(layer "F.Fab")
			(hide yes)
			(effects
				(font
					(size 1.27 1.27)
					(thickness 0.15)
				)
			)
		)
		(property "Description" "SMD Chip Resistor"
			(at 0 0 0)
			(layer "F.Fab")
			(hide yes)
			(effects
				(font
					(size 1.27 1.27)
					(thickness 0.15)
				)
			)
		)
		(property "MPN" "CR0402-FX-4532GLF"
			(at 0 0 180)
			(unlocked yes)
			(layer "F.Fab")
			(hide yes)
			(effects
				(font
					(size 1 1)
					(thickness 0.15)
				)
			)
		)
		(property "Manufacturer" "Bourns"
			(at 0 0 180)
			(unlocked yes)
			(layer "F.Fab")
			(hide yes)
			(effects
				(font
					(size 1 1)
					(thickness 0.15)
				)
			)
		)
		(property "License" "Apache-2.0"
			(at 0 0 180)
			(unlocked yes)
			(layer "F.Fab")
			(hide yes)
			(effects
				(font
					(size 1 1)
					(thickness 0.15)
				)
			)
		)
		(property "Author" "Antmicro"
			(at 0 0 180)
			(unlocked yes)
			(layer "F.Fab")
			(hide yes)
			(effects
				(font
					(size 1 1)
					(thickness 0.15)
				)
			)
		)
		(property "Val" "45k3"
			(at 0 0 180)
			(unlocked yes)
			(layer "F.Fab")
			(hide yes)
			(effects
				(font
					(size 1 1)
					(thickness 0.15)
				)
			)
		)
		(property "Tolerance" "1%"
			(at 0 0 180)
			(unlocked yes)
			(layer "F.Fab")
			(hide yes)
			(effects
				(font
					(size 1 1)
					(thickness 0.15)
				)
			)
		)
		(sheetname "/DCDC/")
		(sheetfile "dcdc.kicad_sch")
		(attr smd)
		(fp_rect
			(start -0.925 -0.47)
			(end 0.925 0.47)
			(stroke
				(width 0.05)
				(type default)
			)
			(fill no)
			(layer "F.CrtYd")
		)
		(fp_rect
			(start -0.5 -0.25)
			(end 0.5 0.25)
			(stroke
				(width 0.15)
				(type solid)
			)
			(fill no)
			(layer "F.Fab")
		)
		(fp_text user "Author: Antmicro"
			(at -0.95 4.169 0)
			(layer "F.Fab")
			(effects
				(font
					(size 0.7 0.7)
					(thickness 0.15)
				)
				(justify right top)
			)
		)
		(fp_text user "License: Apache-2.0"
			(at -0.95 5.169 0)
			(layer "F.Fab")
			(effects
				(font
					(size 0.7 0.7)
					(thickness 0.15)
				)
				(justify right top)
			)
		)
		(fp_text user "${REFERENCE}"
			(at -0.95 3.168 0)
			(layer "F.Fab")
			(effects
				(font
					(size 0.7 0.7)
					(thickness 0.15)
				)
				(justify right top)
			)
		)
		(pad "1" smd roundrect
			(at -0.48 0 180)
			(size 0.59 0.64)
			(layers "F.Cu" "F.Mask" "F.Paste")
			(roundrect_rratio 0.25)
			(net 1218 "/DCDC/3V3_FB")
			(pintype "passive")
		)
		(pad "2" smd roundrect
			(at 0.48 0 180)
			(size 0.59 0.64)
			(layers "F.Cu" "F.Mask" "F.Paste")
			(roundrect_rratio 0.25)
			(net 567 "/DCDC/3V3_OUT")
			(pintype "passive")
		)
	)
	(footprint "antmicro-footprints:C_0402_1005Metric"
		(layer "F.Cu")
		(at 153.499999 96 180)
		(descr "Capacitor SMD 0402")
		(tags "capacitor SMD 0402")
		(property "Reference" "C355"
			(at -1.700001 1.4 0)
			(layer "F.SilkS")
			(effects
				(font
					(size 0.7 0.7)
					(thickness 0.15)
				)
				(justify right top)
			)
		)
		(property "Value" "C_100n_0402"
			(at -1.022927 2.155213 0)
			(layer "F.Fab")
			(effects
				(font
					(size 0.7 0.7)
					(thickness 0.15)
				)
				(justify right top)
			)
		)
		(property "Datasheet" "https://www.murata.com/products/productdetail?partno=GRM155R61H104KE14%23"
			(at 0 0 0)
			(layer "F.Fab")
			(hide yes)
			(effects
				(font
					(size 1.27 1.27)
					(thickness 0.15)
				)
			)
		)
		(property "Description" "SMD Multilayer Ceramic Capacitor, 0.1 µF, 50 V, 0402 [1005 Metric], ± 10%, X5R, GRM Series"
			(at 0 0 0)
			(layer "F.Fab")
			(hide yes)
			(effects
				(font
					(size 1.27 1.27)
					(thickness 0.15)
				)
			)
		)
		(property "Manufacturer" "Murata"
			(at 0 0 180)
			(unlocked yes)
			(layer "F.Fab")
			(hide yes)
			(effects
				(font
					(size 1 1)
					(thickness 0.15)
				)
			)
		)
		(property "MPN" "GRM155R61H104KE14D"
			(at 0 0 180)
			(unlocked yes)
			(layer "F.Fab")
			(hide yes)
			(effects
				(font
					(size 1 1)
					(thickness 0.15)
				)
			)
		)
		(property "Val" "100n"
			(at 0 0 180)
			(unlocked yes)
			(layer "F.Fab")
			(hide yes)
			(effects
				(font
					(size 1 1)
					(thickness 0.15)
				)
			)
		)
		(property "License" "Apache-2.0"
			(at 0 0 180)
			(unlocked yes)
			(layer "F.Fab")
			(hide yes)
			(effects
				(font
					(size 1 1)
					(thickness 0.15)
				)
			)
		)
		(property "Author" "Antmicro"
			(at 0 0 180)
			(unlocked yes)
			(layer "F.Fab")
			(hide yes)
			(effects
				(font
					(size 1 1)
					(thickness 0.15)
				)
			)
		)
		(property "Voltage" "50V"
			(at 0 0 180)
			(unlocked yes)
			(layer "F.Fab")
			(hide yes)
			(effects
				(font
					(size 1 1)
					(thickness 0.15)
				)
			)
		)
		(property "Dielectric" "X5R"
			(at 0 0 180)
			(unlocked yes)
			(layer "F.Fab")
			(hide yes)
			(effects
				(font
					(size 1 1)
					(thickness 0.15)
				)
			)
		)
		(sheetname "/SoM_IO/")
		(sheetfile "som_io.kicad_sch")
		(attr smd)
		(fp_poly
			(pts
				(xy -0.925 -0.47) (xy 0.925 -0.47) (xy 0.925 0.47) (xy -0.925 0.47)
			)
			(stroke
				(width 0.05)
				(type default)
			)
			(fill no)
			(layer "F.CrtYd")
		)
		(fp_line
			(start 0.504 0.248)
			(end -0.494 0.248)
			(stroke
				(width 0.15)
				(type solid)
			)
			(layer "F.Fab")
		)
		(fp_line
			(start 0.504 -0.25)
			(end 0.504 0.248)
			(stroke
				(width 0.15)
				(type solid)
			)
			(layer "F.Fab")
		)
		(fp_line
			(start -0.494 0.248)
			(end -0.494 -0.25)
			(stroke
				(width 0.15)
				(type solid)
			)
			(layer "F.Fab")
		)
		(fp_line
			(start -0.494 -0.25)
			(end 0.504 -0.25)
			(stroke
				(width 0.15)
				(type solid)
			)
			(layer "F.Fab")
		)
		(fp_text user "Author: Antmicro"
			(at -0.939 3.399 0)
			(layer "F.Fab")
			(effects
				(font
					(size 0.7 0.7)
					(thickness 0.15)
				)
				(justify right top)
			)
		)
		(fp_text user "${REFERENCE}"
			(at -0.939 4.599 0)
			(layer "F.Fab")
			(effects
				(font
					(size 0.7 0.7)
					(thickness 0.15)
				)
				(justify right top)
			)
		)
		(fp_text user "License: Apache-2.0"
			(at -0.939 5.799 0)
			(layer "F.Fab")
			(effects
				(font
					(size 0.7 0.7)
					(thickness 0.15)
				)
				(justify right top)
			)
		)
		(pad "1" smd roundrect
			(at -0.48 0 180)
			(size 0.59 0.64)
			(layers "F.Cu" "F.Mask" "F.Paste")
			(roundrect_rratio 0.25)
			(net 1 "GND")
			(pintype "passive")
		)
		(pad "2" smd roundrect
			(at 0.48 0 180)
			(size 0.59 0.64)
			(layers "F.Cu" "F.Mask" "F.Paste")
			(roundrect_rratio 0.25)
			(net 2 "+3V3")
			(pintype "passive")
		)
	)
	(footprint "antmicro-footprints:C_0402_1005Metric"
		(layer "F.Cu")
		(at 211 101.38)
		(descr "Capacitor SMD 0402")
		(tags "capacitor SMD 0402")
		(property "Reference" "C252"
			(at -3.79 0.33 0)
			(layer "F.SilkS")
			(effects
				(font
					(size 0.7 0.7)
					(thickness 0.15)
				)
				(justify left bottom)
			)
		)
		(property "Value" "C_100n_0402"
			(at -1.022927 2.155213 0)
			(layer "F.Fab")
			(effects
				(font
					(size 0.7 0.7)
					(thickness 0.15)
				)
				(justify left bottom)
			)
		)
		(property "Datasheet" "https://www.murata.com/products/productdetail?partno=GRM155R61H104KE14%23"
			(at 0 0 0)
			(layer "F.Fab")
			(hide yes)
			(effects
				(font
					(size 1.27 1.27)
					(thickness 0.15)
				)
			)
		)
		(property "Description" "SMD Multilayer Ceramic Capacitor, 0.1 µF, 50 V, 0402 [1005 Metric], ± 10%, X5R, GRM Series"
			(at 0 0 0)
			(layer "F.Fab")
			(hide yes)
			(effects
				(font
					(size 1.27 1.27)
					(thickness 0.15)
				)
			)
		)
		(property "Manufacturer" "Murata"
			(at 0 0 0)
			(unlocked yes)
			(layer "F.Fab")
			(hide yes)
			(effects
				(font
					(size 1 1)
					(thickness 0.15)
				)
			)
		)
		(property "MPN" "GRM155R61H104KE14D"
			(at 0 0 0)
			(unlocked yes)
			(layer "F.Fab")
			(hide yes)
			(effects
				(font
					(size 1 1)
					(thickness 0.15)
				)
			)
		)
		(property "Val" "100n"
			(at 0 0 0)
			(unlocked yes)
			(layer "F.Fab")
			(hide yes)
			(effects
				(font
					(size 1 1)
					(thickness 0.15)
				)
			)
		)
		(property "License" "Apache-2.0"
			(at 0 0 0)
			(unlocked yes)
			(layer "F.Fab")
			(hide yes)
			(effects
				(font
					(size 1 1)
					(thickness 0.15)
				)
			)
		)
		(property "Author" "Antmicro"
			(at 0 0 0)
			(unlocked yes)
			(layer "F.Fab")
			(hide yes)
			(effects
				(font
					(size 1 1)
					(thickness 0.15)
				)
			)
		)
		(property "Voltage" "50V"
			(at 0 0 0)
			(unlocked yes)
			(layer "F.Fab")
			(hide yes)
			(effects
				(font
					(size 1 1)
					(thickness 0.15)
				)
			)
		)
		(property "Dielectric" "X5R"
			(at 0 0 0)
			(unlocked yes)
			(layer "F.Fab")
			(hide yes)
			(effects
				(font
					(size 1 1)
					(thickness 0.15)
				)
			)
		)
		(sheetname "/Recovery USB/")
		(sheetfile "recovery_usb.kicad_sch")
		(attr smd)
		(fp_rect
			(start -0.925 -0.47)
			(end 0.925 0.47)
			(stroke
				(width 0.05)
				(type default)
			)
			(fill no)
			(layer "F.CrtYd")
		)
		(fp_line
			(start -0.494 -0.25)
			(end 0.504 -0.25)
			(stroke
				(width 0.15)
				(type solid)
			)
			(layer "F.Fab")
		)
		(fp_line
			(start -0.494 0.248)
			(end -0.494 -0.25)
			(stroke
				(width 0.15)
				(type solid)
			)
			(layer "F.Fab")
		)
		(fp_line
			(start 0.504 -0.25)
			(end 0.504 0.248)
			(stroke
				(width 0.15)
				(type solid)
			)
			(layer "F.Fab")
		)
		(fp_line
			(start 0.504 0.248)
			(end -0.494 0.248)
			(stroke
				(width 0.15)
				(type solid)
			)
			(layer "F.Fab")
		)
		(fp_text user "License: Apache-2.0"
			(at -0.939 5.799 0)
			(layer "F.Fab")
			(effects
				(font
					(size 0.7 0.7)
					(thickness 0.15)
				)
				(justify left bottom)
			)
		)
		(fp_text user "${REFERENCE}"
			(at -0.939 4.599 0)
			(layer "F.Fab")
			(effects
				(font
					(size 0.7 0.7)
					(thickness 0.15)
				)
				(justify left bottom)
			)
		)
		(fp_text user "Author: Antmicro"
			(at -0.939 3.399 0)
			(layer "F.Fab")
			(effects
				(font
					(size 0.7 0.7)
					(thickness 0.15)
				)
				(justify left bottom)
			)
		)
		(pad "1" smd roundrect
			(at -0.48 0)
			(size 0.59 0.64)
			(layers "F.Cu" "F.Mask" "F.Paste")
			(roundrect_rratio 0.25)
			(net 630 "/Recovery USB/USBSS0.TX-")
			(pintype "passive")
		)
		(pad "2" smd roundrect
			(at 0.48 0)
			(size 0.59 0.64)
			(layers "F.Cu" "F.Mask" "F.Paste")
			(roundrect_rratio 0.25)
			(net 1131 "/Recovery USB/USBSS_TX_P")
			(pintype "passive")
		)
	)
	(footprint "antmicro-footprints:SOD-523"
		(layer "F.Cu")
		(at 168.2 150.4)
		(property "Reference" "D39"
			(at -1.101 1.5 0)
			(layer "F.SilkS")
			(effects
				(font
					(size 0.7 0.7)
					(thickness 0.15)
				)
				(justify left bottom)
			)
		)
		(property "Value" "PESD5Z5.0F"
			(at 0 1.499 0)
			(layer "F.Fab")
			(effects
				(font
					(size 0.7 0.7)
					(thickness 0.15)
				)
				(justify left bottom)
			)
		)
		(property "Datasheet" "https://assets.nexperia.com/documents/data-sheet/PESD5Z5_0.pdf"
			(at 0 0 0)
			(layer "F.Fab")
			(hide yes)
			(effects
				(font
					(size 1.27 1.27)
					(thickness 0.15)
				)
			)
		)
		(property "Description" "Unidirectional TVS, 30 kV,  SOD-523, 5 V, 89 pF"
			(at 0 0 0)
			(layer "F.Fab")
			(hide yes)
			(effects
				(font
					(size 1.27 1.27)
					(thickness 0.15)
				)
			)
		)
		(property "Manufacturer" "Nexperia"
			(at 0 0 0)
			(unlocked yes)
			(layer "F.Fab")
			(hide yes)
			(effects
				(font
					(size 1 1)
					(thickness 0.15)
				)
			)
		)
		(property "MPN" "PESD5Z5.0F"
			(at 0 0 0)
			(unlocked yes)
			(layer "F.Fab")
			(hide yes)
			(effects
				(font
					(size 1 1)
					(thickness 0.15)
				)
			)
		)
		(property "Author" "Antmicro"
			(at 0 0 0)
			(unlocked yes)
			(layer "F.Fab")
			(hide yes)
			(effects
				(font
					(size 1 1)
					(thickness 0.15)
				)
			)
		)
		(property "License" "Apache-2.0"
			(at 0 0 0)
			(unlocked yes)
			(layer "F.Fab")
			(hide yes)
			(effects
				(font
					(size 1 1)
					(thickness 0.15)
				)
			)
		)
		(sheetname "/Peripherals/")
		(sheetfile "peripherals.kicad_sch")
		(attr smd)
		(fp_line
			(start -0.35 -0.5)
			(end -0.35 0.5)
			(stroke
				(width 0.15)
				(type solid)
			)
			(layer "F.SilkS")
		)
		(fp_rect
			(start -1 -0.6)
			(end 1 0.6)
			(stroke
				(width 0.05)
				(type solid)
			)
			(fill no)
			(layer "F.CrtYd")
		)
		(fp_line
			(start -0.652 -0.425)
			(end 0.65 -0.425)
			(stroke
				(width 0.15)
				(type solid)
			)
			(layer "F.Fab")
		)
		(fp_line
			(start -0.652 0.423)
			(end -0.652 -0.425)
			(stroke
				(width 0.15)
				(type solid)
			)
			(layer "F.Fab")
		)
		(fp_line
			(start -0.652 0.423)
			(end 0.65 0.423)
			(stroke
				(width 0.15)
				(type solid)
			)
			(layer "F.Fab")
		)
		(fp_line
			(start -0.35 -0.4)
			(end -0.35 0.4)
			(stroke
				(width 0.15)
				(type solid)
			)
			(layer "F.Fab")
		)
		(fp_line
			(start 0.65 -0.425)
			(end 0.65 0.423)
			(stroke
				(width 0.15)
				(type solid)
			)
			(layer "F.Fab")
		)
		(fp_text user "License: Apache-2.0"
			(at -1.276 5.9 0)
			(layer "F.Fab")
			(effects
				(font
					(size 0.7 0.7)
					(thickness 0.15)
				)
				(justify left bottom)
			)
		)
		(fp_text user "Author: Antmicro"
			(at -1.276 4.7 0)
			(layer "F.Fab")
			(effects
				(font
					(size 0.7 0.7)
					(thickness 0.15)
				)
				(justify left bottom)
			)
		)
		(fp_text user "${REFERENCE}"
			(at -1.276 3.499 0)
			(layer "F.Fab")
			(effects
				(font
					(size 0.7 0.7)
					(thickness 0.15)
				)
				(justify left bottom)
			)
		)
		(pad "1" smd roundrect
			(at -0.701 0)
			(size 0.5 0.6)
			(layers "F.Cu" "F.Mask" "F.Paste")
			(roundrect_rratio 0.25)
			(net 5 "+5V")
			(pinfunction "C")
			(pintype "passive")
		)
		(pad "2" smd roundrect
			(at 0.699 0)
			(size 0.5 0.6)
			(layers "F.Cu" "F.Mask" "F.Paste")
			(roundrect_rratio 0.25)
			(net 1 "GND")
			(pinfunction "A")
			(pintype "passive")
		)
	)
	(footprint "antmicro-footprints:C_0402_1005Metric"
		(layer "F.Cu")
		(at 186.2 122.299 180)
		(descr "Capacitor SMD 0402")
		(tags "capacitor SMD 0402")
		(property "Reference" "C111"
			(at 0.1 1.599 0)
			(layer "F.SilkS")
			(effects
				(font
					(size 0.7 0.7)
					(thickness 0.15)
				)
				(justify right top)
			)
		)
		(property "Value" "C_100n_0402"
			(at -1.022927 2.155213 0)
			(layer "F.Fab")
			(effects
				(font
					(size 0.7 0.7)
					(thickness 0.15)
				)
				(justify right top)
			)
		)
		(property "Datasheet" "https://www.murata.com/products/productdetail?partno=GRM155R61H104KE14%23"
			(at 0 0 0)
			(layer "F.Fab")
			(hide yes)
			(effects
				(font
					(size 1.27 1.27)
					(thickness 0.15)
				)
			)
		)
		(property "Description" "SMD Multilayer Ceramic Capacitor, 0.1 µF, 50 V, 0402 [1005 Metric], ± 10%, X5R, GRM Series"
			(at 0 0 0)
			(layer "F.Fab")
			(hide yes)
			(effects
				(font
					(size 1.27 1.27)
					(thickness 0.15)
				)
			)
		)
		(property "Manufacturer" "Murata"
			(at 0 0 180)
			(unlocked yes)
			(layer "F.Fab")
			(hide yes)
			(effects
				(font
					(size 1 1)
					(thickness 0.15)
				)
			)
		)
		(property "MPN" "GRM155R61H104KE14D"
			(at 0 0 180)
			(unlocked yes)
			(layer "F.Fab")
			(hide yes)
			(effects
				(font
					(size 1 1)
					(thickness 0.15)
				)
			)
		)
		(property "Val" "100n"
			(at 0 0 180)
			(unlocked yes)
			(layer "F.Fab")
			(hide yes)
			(effects
				(font
					(size 1 1)
					(thickness 0.15)
				)
			)
		)
		(property "License" "Apache-2.0"
			(at 0 0 180)
			(unlocked yes)
			(layer "F.Fab")
			(hide yes)
			(effects
				(font
					(size 1 1)
					(thickness 0.15)
				)
			)
		)
		(property "Author" "Antmicro"
			(at 0 0 180)
			(unlocked yes)
			(layer "F.Fab")
			(hide yes)
			(effects
				(font
					(size 1 1)
					(thickness 0.15)
				)
			)
		)
		(property "Voltage" "50V"
			(at 0 0 180)
			(unlocked yes)
			(layer "F.Fab")
			(hide yes)
			(effects
				(font
					(size 1 1)
					(thickness 0.15)
				)
			)
		)
		(property "Dielectric" "X5R"
			(at 0 0 180)
			(unlocked yes)
			(layer "F.Fab")
			(hide yes)
			(effects
				(font
					(size 1 1)
					(thickness 0.15)
				)
			)
		)
		(sheetname "/USB Hub/")
		(sheetfile "usb_hub.kicad_sch")
		(attr smd)
		(fp_poly
			(pts
				(xy -0.925 -0.47) (xy 0.925 -0.47) (xy 0.925 0.47) (xy -0.925 0.47)
			)
			(stroke
				(width 0.05)
				(type default)
			)
			(fill no)
			(layer "F.CrtYd")
		)
		(fp_line
			(start 0.504 0.248)
			(end -0.494 0.248)
			(stroke
				(width 0.15)
				(type solid)
			)
			(layer "F.Fab")
		)
		(fp_line
			(start 0.504 -0.25)
			(end 0.504 0.248)
			(stroke
				(width 0.15)
				(type solid)
			)
			(layer "F.Fab")
		)
		(fp_line
			(start -0.494 0.248)
			(end -0.494 -0.25)
			(stroke
				(width 0.15)
				(type solid)
			)
			(layer "F.Fab")
		)
		(fp_line
			(start -0.494 -0.25)
			(end 0.504 -0.25)
			(stroke
				(width 0.15)
				(type solid)
			)
			(layer "F.Fab")
		)
		(fp_text user "License: Apache-2.0"
			(at -0.939 5.799 0)
			(layer "F.Fab")
			(effects
				(font
					(size 0.7 0.7)
					(thickness 0.15)
				)
				(justify right top)
			)
		)
		(fp_text user "${REFERENCE}"
			(at -0.939 4.599 0)
			(layer "F.Fab")
			(effects
				(font
					(size 0.7 0.7)
					(thickness 0.15)
				)
				(justify right top)
			)
		)
		(fp_text user "Author: Antmicro"
			(at -0.939 3.399 0)
			(layer "F.Fab")
			(effects
				(font
					(size 0.7 0.7)
					(thickness 0.15)
				)
				(justify right top)
			)
		)
		(pad "1" smd roundrect
			(at -0.48 0 180)
			(size 0.59 0.64)
			(layers "F.Cu" "F.Mask" "F.Paste")
			(roundrect_rratio 0.25)
			(net 1 "GND")
			(pintype "passive")
		)
		(pad "2" smd roundrect
			(at 0.48 0 180)
			(size 0.59 0.64)
			(layers "F.Cu" "F.Mask" "F.Paste")
			(roundrect_rratio 0.25)
			(net 271 "FLASH_PWR")
			(pintype "passive")
		)
	)
)
